(kicad_pcb
	(version 20260206)
	(generator "pcbnew")
	(generator_version "10.0")
	(general
		(thickness 1.6)
		(legacy_teardrops no)
	)
	(paper "A4")
	(title_block
		(title "fcb — Lightning_FCB_BRD.brd")
		(comment 1 "Lightning (Wiwynn / Facebook NVMe JBOF) / footprints 60-65 of 495")
	)
	(layers
		(0 "F.Cu" signal "TOP")
		(4 "In1.Cu" signal "L2GND")
		(6 "In2.Cu" signal "L3VCC")
		(2 "B.Cu" signal "BOTTOM")
		(9 "F.Adhes" user "F.Adhesive")
		(11 "B.Adhes" user "B.Adhesive")
		(13 "F.Paste" user "Package Geometry/Pastemask Top")
		(15 "B.Paste" user "Package Geometry/Pastemask Bottom")
		(5 "F.SilkS" user "Ref Des/Silkscreen Top")
		(7 "B.SilkS" user "Ref Des/Silkscreen Bottom")
		(1 "F.Mask" user "Board Geometry/Soldermask Top")
		(3 "B.Mask" user "Board Geometry/Soldermask Bottom")
		(17 "Dwgs.User" user "User.Drawings")
		(19 "Cmts.User" user "User.Comments")
		(21 "Eco1.User" user "User.Eco1")
		(23 "Eco2.User" user "User.Eco2")
		(25 "Edge.Cuts" user "Board Geometry/Outline")
		(27 "Margin" user)
		(31 "F.CrtYd" user "Package Geometry/Place Bound Top")
		(29 "B.CrtYd" user "Package Geometry/Place Bound Bottom")
		(35 "F.Fab" user "Ref Des/Assembly Top")
		(33 "B.Fab" user "Ref Des/Assembly Bottom")
	)
	(footprint ""
		(layer "F.Cu")
		(at 19.431 -111.76)
		(property "Reference" "PQ11"
			(at 0 0 0)
			(layer "F.SilkS")
			(hide yes)
			(effects
				(font
					(size 1.27 1.27)
				)
			)
		)
		(property "Value" "PH0925CL-GP"
			(at -4.2799 -0.4572 0)
			(unlocked yes)
			(layer "F.Fab")
			(hide yes)
			(effects
				(font
					(size 1.016 1.016)
					(thickness 0.1524)
				)
			)
		)
		(property "Device Type" "LFPAK-5PH48-U"
			(at -4.2799 -1.9812 0)
			(unlocked yes)
			(layer "F.Fab")
			(hide yes)
			(effects
				(font
					(size 1.016 1.016)
					(thickness 0.1524)
				)
			)
		)
		(duplicate_pad_numbers_are_jumpers no)
		(fp_line
			(start -2.7559 -6.5532)
			(end -2.7559 1.0668)
			(stroke
				(width 0.1524)
				(type default)
			)
			(layer "F.SilkS")
		)
		(fp_line
			(start -2.7559 1.0668)
			(end 2.7559 1.0668)
			(stroke
				(width 0.1524)
				(type default)
			)
			(layer "F.SilkS")
		)
		(fp_line
			(start -1.7272 1.1684)
			(end -2.1082 1.1684)
			(stroke
				(width 0.3302)
				(type default)
			)
			(layer "F.SilkS")
		)
		(fp_line
			(start 2.7559 -6.5532)
			(end -2.7559 -6.5532)
			(stroke
				(width 0.1524)
				(type default)
			)
			(layer "F.SilkS")
		)
		(fp_line
			(start 2.7559 1.0668)
			(end 2.7559 -6.5532)
			(stroke
				(width 0.1524)
				(type default)
			)
			(layer "F.SilkS")
		)
		(fp_poly
			(pts
				(xy -2.3368 1.5748) (xy -1.905 1.143) (xy -1.4732 1.5748)
			)
			(stroke
				(width 0)
				(type default)
			)
			(fill yes)
			(layer "F.SilkS")
		)
		(fp_poly
			(pts
				(xy -2.5019 -4.02971) (xy -0.3302 -4.02971) (xy -0.3302 -6.30301) (xy -2.5019 -6.30301)
			)
			(stroke
				(width 0)
				(type default)
			)
			(fill yes)
			(layer "F.Paste")
		)
		(fp_poly
			(pts
				(xy -2.5019 -1.09601) (xy -0.3302 -1.09601) (xy -0.3302 -3.36931) (xy -2.5019 -3.36931)
			)
			(stroke
				(width 0)
				(type default)
			)
			(fill yes)
			(layer "F.Paste")
		)
		(fp_poly
			(pts
				(xy 0.3302 -4.02971) (xy 2.5019 -4.02971) (xy 2.5019 -6.30301) (xy 0.3302 -6.30301)
			)
			(stroke
				(width 0)
				(type default)
			)
			(fill yes)
			(layer "F.Paste")
		)
		(fp_poly
			(pts
				(xy 0.3302 -1.09601) (xy 2.5019 -1.09601) (xy 2.5019 -3.36931) (xy 0.3302 -3.36931)
			)
			(stroke
				(width 0)
				(type default)
			)
			(fill yes)
			(layer "F.Paste")
		)
		(fp_rect
			(start -2.4511 0.3048)
			(end 2.4511 -5.6896)
			(stroke
				(width 0)
				(type default)
			)
			(fill no)
			(layer "F.CrtYd")
		)
		(fp_poly
			(pts
				(xy -3.0099 1.3208) (xy -3.0099 -6.8072) (xy 3.0099 -6.8072) (xy 3.0099 -1.016) (xy 2.4511 -1.016)
				(xy 2.4511 -5.6896) (xy -2.4511 -5.6896) (xy -2.4511 0.3048) (xy 2.4511 0.3048) (xy 2.4511 -1.0033)
				(xy 3.0099 -1.0033) (xy 3.0099 1.3208)
			)
			(stroke
				(width 0)
				(type default)
			)
			(fill no)
			(layer "F.CrtYd")
		)
		(fp_rect
			(start -3.0099 1.3208)
			(end 3.0099 -6.8072)
			(stroke
				(width 0)
				(type default)
			)
			(fill no)
			(layer "F.Fab")
		)
		(pad "1" smd rect
			(at -1.905 0)
			(size 0.762 1.6256)
			(layers "F.Cu" "F.Mask" "F.Paste")
			(net "P12VU")
		)
		(pad "2" smd rect
			(at -0.635 0)
			(size 0.762 1.6256)
			(layers "F.Cu" "F.Mask" "F.Paste")
			(net "P12VU")
		)
		(pad "3" smd rect
			(at 0.635 0)
			(size 0.762 1.6256)
			(layers "F.Cu" "F.Mask" "F.Paste")
			(net "P12VU")
		)
		(pad "4" smd rect
			(at 1.905 0)
			(size 0.762 1.6256)
			(layers "F.Cu" "F.Mask" "F.Paste")
			(net "P12VU_2490_GATE_DRV_2")
		)
		(pad "5" smd rect
			(at 0 -3.69951)
			(size 5.0038 5.207)
			(layers "F.Cu" "F.Mask" "F.Paste")
			(net "P12VU_NET")
		)
	)
	(footprint ""
		(layer "F.Cu")
		(at 8.9662 -101.0412 -90)
		(property "Reference" "TC1"
			(at 0 0 270)
			(layer "F.SilkS")
			(hide yes)
			(effects
				(font
					(size 1.27 1.27)
				)
			)
		)
		(property "Value" "ST68U16VDM-1-GP"
			(at 0 -9.6012 270)
			(unlocked yes)
			(layer "F.Fab")
			(hide yes)
			(effects
				(font
					(size 1.016 1.016)
					(thickness 0.1524)
				)
			)
		)
		(property "Device Type" "CT7343H79"
			(at 0 -11.1252 270)
			(unlocked yes)
			(layer "F.Fab")
			(hide yes)
			(effects
				(font
					(size 1.016 1.016)
					(thickness 0.1524)
				)
			)
		)
		(duplicate_pad_numbers_are_jumpers no)
		(fp_line
			(start -2.286 4.8768)
			(end -2.286 2.032)
			(stroke
				(width 0.1524)
				(type default)
			)
			(layer "F.SilkS")
		)
		(fp_line
			(start 2.286 4.8768)
			(end -2.286 4.8768)
			(stroke
				(width 0.1524)
				(type default)
			)
			(layer "F.SilkS")
		)
		(fp_line
			(start 2.286 2.032)
			(end 2.286 4.8768)
			(stroke
				(width 0.1524)
				(type default)
			)
			(layer "F.SilkS")
		)
		(fp_line
			(start 2.286 -2.032)
			(end 2.286 -4.8768)
			(stroke
				(width 0.1524)
				(type default)
			)
			(layer "F.SilkS")
		)
		(fp_line
			(start 2.1082 -4.699)
			(end -2.1082 -4.699)
			(stroke
				(width 0.508)
				(type default)
			)
			(layer "F.SilkS")
		)
		(fp_line
			(start -2.286 -4.8768)
			(end -2.286 -2.032)
			(stroke
				(width 0.1524)
				(type default)
			)
			(layer "F.SilkS")
		)
		(fp_line
			(start 2.286 -4.8768)
			(end -2.286 -4.8768)
			(stroke
				(width 0.1524)
				(type default)
			)
			(layer "F.SilkS")
		)
		(fp_rect
			(start -2.1463 3.6449)
			(end 2.1463 -3.6449)
			(stroke
				(width 0)
				(type default)
			)
			(fill no)
			(layer "F.CrtYd")
		)
		(fp_poly
			(pts
				(xy -2.54 4.953) (xy -2.54 4.2926) (xy -3.81 4.2926) (xy -3.81 -4.2926) (xy -2.54 -4.2926) (xy -2.54 -4.953)
				(xy 2.54 -4.953) (xy 2.54 -4.2926) (xy 3.81 -4.2926) (xy 3.81 -1.6256) (xy 2.1463 -1.6256) (xy 2.1463 -3.6449)
				(xy -2.1463 -3.6449) (xy -2.1463 3.6449) (xy 2.1463 3.6449) (xy 2.1463 -1.6129) (xy 3.81 -1.6129)
				(xy 3.81 4.2926) (xy 2.54 4.2926) (xy 2.54 4.953)
			)
			(stroke
				(width 0)
				(type default)
			)
			(fill no)
			(layer "F.CrtYd")
		)
		(fp_rect
			(start -2.54 4.953)
			(end 2.54 -4.953)
			(stroke
				(width 0)
				(type default)
			)
			(fill no)
			(layer "F.Fab")
		)
		(fp_rect
			(start -3.81 4.2926)
			(end -2.54 -4.2926)
			(stroke
				(width 0)
				(type default)
			)
			(fill no)
			(layer "F.Fab")
		)
		(fp_rect
			(start 2.54 4.2926)
			(end 3.81 -4.2926)
			(stroke
				(width 0)
				(type default)
			)
			(fill no)
			(layer "F.Fab")
		)
		(pad "1" smd rect
			(at 0 -3.1496 270)
			(size 2.413 2.286)
			(layers "F.Cu" "F.Mask" "F.Paste")
			(net "P12VU")
		)
		(pad "2" smd rect
			(at 0 3.1496 270)
			(size 2.413 2.286)
			(layers "F.Cu" "F.Mask" "F.Paste")
			(net "GND")
		)
		(zone
			(layer "F.Cu")
			(hatch none 0.5)
			(connect_pads
				(clearance 0)
			)
			(min_thickness 0.25)
			(keepout
				(tracks allowed)
				(vias not_allowed)
				(pads allowed)
				(copperpour not_allowed)
				(footprints allowed)
			)
			(placement
				(enabled no)
				(sheetname "")
			)
			(fill
				(thermal_gap 0.5)
				(thermal_bridge_width 0.5)
				(island_removal_mode 0)
			)
			(polygon
				(pts
					(xy 4.3688 -102.5525) (xy 4.3688 -99.5299) (xy 7.2644 -99.5299) (xy 7.5946 -99.5299) (xy 7.5946 -102.5525)
					(xy 7.2644 -102.5525)
				)
			)
		)
		(zone
			(layer "F.Cu")
			(hatch none 0.5)
			(connect_pads
				(clearance 0)
			)
			(min_thickness 0.25)
			(keepout
				(tracks allowed)
				(vias not_allowed)
				(pads allowed)
				(copperpour not_allowed)
				(footprints allowed)
			)
			(placement
				(enabled no)
				(sheetname "")
			)
			(fill
				(thermal_gap 0.5)
				(thermal_bridge_width 0.5)
				(island_removal_mode 0)
			)
			(polygon
				(pts
					(xy 10.6553 -99.5299) (xy 13.5636 -99.5299) (xy 13.5636 -102.5525) (xy 10.668 -102.5525) (xy 10.3378 -102.5525)
					(xy 10.3378 -99.5299)
				)
			)
		)
	)
	(footprint ""
		(layer "F.Cu")
		(at 33.51149 -152.889966 180)
		(property "Reference" "TP10"
			(at 0 0 180)
			(layer "F.SilkS")
			(hide yes)
			(effects
				(font
					(size 1.27 1.27)
				)
			)
		)
		(property "Value" "TPAD32-GP"
			(at 0 -3.166364 180)
			(unlocked yes)
			(layer "F.Fab")
			(hide yes)
			(effects
				(font
					(size 1.016 1.016)
					(thickness 0.1524)
				)
			)
		)
		(property "Device Type" "TPAD32"
			(at 0 -4.690618 180)
			(unlocked yes)
			(layer "F.Fab")
			(hide yes)
			(effects
				(font
					(size 1.016 1.016)
					(thickness 0.1524)
				)
			)
		)
		(duplicate_pad_numbers_are_jumpers no)
		(fp_poly
			(pts
				(arc
					(start 0.7112 0)
					(mid -0.7112 0)
					(end 0.7112 0)
				)
			)
			(stroke
				(width 0)
				(type default)
			)
			(fill no)
			(layer "F.CrtYd")
		)
		(fp_poly
			(pts
				(arc
					(start 0.7112 0)
					(mid -0.7112 0)
					(end 0.7112 0)
				)
			)
			(stroke
				(width 0)
				(type default)
			)
			(fill no)
			(layer "F.Fab")
		)
		(pad "1" smd circle
			(at 0 0 180)
			(size 0.8128 0.8128)
			(layers "F.Cu" "F.Mask" "F.Paste")
			(net "NCT7904_VSEN11")
		)
	)
	(footprint ""
		(layer "F.Cu")
		(at 37.719 -373.9896 180)
		(property "Reference" "PR25"
			(at 0 0 180)
			(layer "F.SilkS")
			(hide yes)
			(effects
				(font
					(size 1.27 1.27)
				)
			)
		)
		(property "Value" "0R2J-2-GP"
			(at 0.064008 -3.993896 180)
			(unlocked yes)
			(layer "F.Fab")
			(hide yes)
			(effects
				(font
					(size 1.016 1.016)
					(thickness 0.1524)
				)
			)
		)
		(property "Device Type" "R402H16"
			(at 0.064008 -5.517896 180)
			(unlocked yes)
			(layer "F.Fab")
			(hide yes)
			(effects
				(font
					(size 1.016 1.016)
					(thickness 0.1524)
				)
			)
		)
		(duplicate_pad_numbers_are_jumpers no)
		(fp_line
			(start 0.508 -0.9398)
			(end -0.508 -0.9398)
			(stroke
				(width 0.1524)
				(type default)
			)
			(layer "F.SilkS")
		)
		(fp_line
			(start -0.508 -0.9398)
			(end -0.508 0.9398)
			(stroke
				(width 0.1524)
				(type default)
			)
			(layer "F.SilkS")
		)
		(fp_rect
			(start -0.508 0.9398)
			(end 0.508 -0.9398)
			(stroke
				(width 0)
				(type default)
			)
			(fill no)
			(layer "F.CrtYd")
		)
		(fp_rect
			(start -0.508 0.9398)
			(end 0.508 -0.9398)
			(stroke
				(width 0)
				(type default)
			)
			(fill no)
			(layer "F.Fab")
		)
		(pad "1" smd custom
			(at 0 -0.4445 180)
			(size 0.1397 0.1397)
			(layers "F.Cu" "F.Mask" "F.Paste")
			(net "P12V")
			(options
				(clearance outline)
				(anchor circle)
			)
			(primitives
				(gr_poly
					(pts
						(arc
							(start -0.1778 -0.2794)
							(mid -0.249642 -0.249642)
							(end -0.2794 -0.1778)
						)
						(arc
							(start -0.2794 0.1778)
							(mid -0.249642 0.249642)
							(end -0.1778 0.2794)
						)
						(arc
							(start 0.1778 0.2794)
							(mid 0.249642 0.249642)
							(end 0.2794 0.1778)
						)
						(arc
							(start 0.2794 -0.1778)
							(mid 0.249642 -0.249642)
							(end 0.1778 -0.2794)
						)
					)
					(width 0)
					(fill yes)
				)
			)
		)
		(pad "2" smd custom
			(at 0 0.4445 180)
			(size 0.1397 0.1397)
			(layers "F.Cu" "F.Mask" "F.Paste")
			(net "ADM1276_GATE_RSV")
			(options
				(clearance outline)
				(anchor circle)
			)
			(primitives
				(gr_poly
					(pts
						(arc
							(start -0.1778 -0.2794)
							(mid -0.249642 -0.249642)
							(end -0.2794 -0.1778)
						)
						(arc
							(start -0.2794 0.1778)
							(mid -0.249642 0.249642)
							(end -0.1778 0.2794)
						)
						(arc
							(start 0.1778 0.2794)
							(mid 0.249642 0.249642)
							(end 0.2794 0.1778)
						)
						(arc
							(start 0.2794 -0.1778)
							(mid 0.249642 -0.249642)
							(end 0.1778 -0.2794)
						)
					)
					(width 0)
					(fill yes)
				)
			)
		)
	)
	(footprint ""
		(layer "F.Cu")
		(at 38.6334 -254.381)
		(property "Reference" "R58"
			(at 0 0 0)
			(layer "F.SilkS")
			(hide yes)
			(effects
				(font
					(size 1.27 1.27)
				)
			)
		)
		(property "Value" "330R2J-3-GP"
			(at 0.064008 -3.993896 0)
			(unlocked yes)
			(layer "F.Fab")
			(hide yes)
			(effects
				(font
					(size 1.016 1.016)
					(thickness 0.1524)
				)
			)
		)
		(property "Device Type" "R402H16"
			(at 0.064008 -5.517896 0)
			(unlocked yes)
			(layer "F.Fab")
			(hide yes)
			(effects
				(font
					(size 1.016 1.016)
					(thickness 0.1524)
				)
			)
		)
		(duplicate_pad_numbers_are_jumpers no)
		(fp_line
			(start -0.508 -0.9398)
			(end -0.508 0.9398)
			(stroke
				(width 0.1524)
				(type default)
			)
			(layer "F.SilkS")
		)
		(fp_line
			(start 0.508 -0.9398)
			(end -0.508 -0.9398)
			(stroke
				(width 0.1524)
				(type default)
			)
			(layer "F.SilkS")
		)
		(fp_rect
			(start -0.508 0.9398)
			(end 0.508 -0.9398)
			(stroke
				(width 0)
				(type default)
			)
			(fill no)
			(layer "F.CrtYd")
		)
		(fp_rect
			(start -0.508 0.9398)
			(end 0.508 -0.9398)
			(stroke
				(width 0)
				(type default)
			)
			(fill no)
			(layer "F.Fab")
		)
		(pad "1" smd custom
			(at 0 -0.4445)
			(size 0.1397 0.1397)
			(layers "F.Cu" "F.Mask" "F.Paste")
			(net "P3V3")
			(options
				(clearance outline)
				(anchor circle)
			)
			(primitives
				(gr_poly
					(pts
						(arc
							(start -0.1778 -0.2794)
							(mid -0.249642 -0.249642)
							(end -0.2794 -0.1778)
						)
						(arc
							(start -0.2794 0.1778)
							(mid -0.249642 0.249642)
							(end -0.1778 0.2794)
						)
						(arc
							(start 0.1778 0.2794)
							(mid 0.249642 0.249642)
							(end 0.2794 0.1778)
						)
						(arc
							(start 0.2794 -0.1778)
							(mid 0.249642 -0.249642)
							(end 0.1778 -0.2794)
						)
					)
					(width 0)
					(fill yes)
				)
			)
		)
		(pad "2" smd custom
			(at 0 0.4445)
			(size 0.1397 0.1397)
			(layers "F.Cu" "F.Mask" "F.Paste")
			(net "LED_DR_LED6_RESERVE")
			(options
				(clearance outline)
				(anchor circle)
			)
			(primitives
				(gr_poly
					(pts
						(arc
							(start -0.1778 -0.2794)
							(mid -0.249642 -0.249642)
							(end -0.2794 -0.1778)
						)
						(arc
							(start -0.2794 0.1778)
							(mid -0.249642 0.249642)
							(end -0.1778 0.2794)
						)
						(arc
							(start 0.1778 0.2794)
							(mid 0.249642 0.249642)
							(end 0.2794 0.1778)
						)
						(arc
							(start 0.2794 -0.1778)
							(mid 0.249642 -0.249642)
							(end 0.1778 -0.2794)
						)
					)
					(width 0)
					(fill yes)
				)
			)
		)
	)
	(footprint ""
		(layer "F.Cu")
		(at 38.5572 -109.4232 -90)
		(property "Reference" "PR103"
			(at 0 0 270)
			(layer "F.SilkS")
			(hide yes)
			(effects
				(font
					(size 1.27 1.27)
				)
			)
		)
		(property "Value" "10R2F-L-GP"
			(at 0.064008 -3.993896 270)
			(unlocked yes)
			(layer "F.Fab")
			(hide yes)
			(effects
				(font
					(size 1.016 1.016)
					(thickness 0.1524)
				)
			)
		)
		(property "Device Type" "R402H14"
			(at 0.064008 -5.517896 270)
			(unlocked yes)
			(layer "F.Fab")
			(hide yes)
			(effects
				(font
					(size 1.016 1.016)
					(thickness 0.1524)
				)
			)
		)
		(duplicate_pad_numbers_are_jumpers no)
		(fp_line
			(start -0.508 -0.9398)
			(end -0.508 0.9398)
			(stroke
				(width 0.1524)
				(type default)
			)
			(layer "F.SilkS")
		)
		(fp_line
			(start 0.508 -0.9398)
			(end -0.508 -0.9398)
			(stroke
				(width 0.1524)
				(type default)
			)
			(layer "F.SilkS")
		)
		(fp_rect
			(start -0.508 0.9398)
			(end 0.508 -0.9398)
			(stroke
				(width 0)
				(type default)
			)
			(fill no)
			(layer "F.CrtYd")
		)
		(fp_rect
			(start -0.508 0.9398)
			(end 0.508 -0.9398)
			(stroke
				(width 0)
				(type default)
			)
			(fill no)
			(layer "F.Fab")
		)
		(pad "1" smd custom
			(at 0 -0.4445 270)
			(size 0.1397 0.1397)
			(layers "F.Cu" "F.Mask" "F.Paste")
			(net "P12VL_2490_GATE_DRV")
			(options
				(clearance outline)
				(anchor circle)
			)
			(primitives
				(gr_poly
					(pts
						(arc
							(start -0.1778 -0.2794)
							(mid -0.249642 -0.249642)
							(end -0.2794 -0.1778)
						)
						(arc
							(start -0.2794 0.1778)
							(mid -0.249642 0.249642)
							(end -0.1778 0.2794)
						)
						(arc
							(start 0.1778 0.2794)
							(mid 0.249642 0.249642)
							(end 0.2794 0.1778)
						)
						(arc
							(start 0.2794 -0.1778)
							(mid 0.249642 -0.249642)
							(end 0.1778 -0.2794)
						)
					)
					(width 0)
					(fill yes)
				)
			)
		)
		(pad "2" smd custom
			(at 0 0.4445 270)
			(size 0.1397 0.1397)
			(layers "F.Cu" "F.Mask" "F.Paste")
			(net "P12VL_2490_GATE")
			(options
				(clearance outline)
				(anchor circle)
			)
			(primitives
				(gr_poly
					(pts
						(arc
							(start -0.1778 -0.2794)
							(mid -0.249642 -0.249642)
							(end -0.2794 -0.1778)
						)
						(arc
							(start -0.2794 0.1778)
							(mid -0.249642 0.249642)
							(end -0.1778 0.2794)
						)
						(arc
							(start 0.1778 0.2794)
							(mid 0.249642 0.249642)
							(end 0.2794 0.1778)
						)
						(arc
							(start 0.2794 -0.1778)
							(mid 0.249642 -0.249642)
							(end 0.1778 -0.2794)
						)
					)
					(width 0)
					(fill yes)
				)
			)
		)
	)
)
